#ISCELL
  mstr_misc dns *
  *
#ISCELL
  pure_quanta quanta_title_block_c *
  *
#ISCELL
  logical_power universal_gnd *
  page275_i1
#ISCELL
  logical_power universal_gnd *
  page275_i10
#CELL
  pure_quanta q_cap *
  page275_i11
#CELL
  pure_quanta q_res *
  page275_i12
#CELL
  pure_quanta q_res *
  page275_i13
#ISCELL
  logical_power vcc15 *
  page275_i14
#ISCELL
  logical_power universal_gnd *
  page275_i15
#CELL
  pure_quanta q_cap *
  page275_i16
#CELL
  pure_quanta q_res *
  page275_i17
#ISCELL
  logical_power vcc15 *
  page275_i18
#ISCELL
  logical_power universal_gnd *
  page275_i19
#CELL
  pure_quanta q_res *
  page275_i2
#CELL
  pure_quanta q_res *
  page275_i20
#ISCELL
  logical_power universal_gnd *
  page275_i21
#ISCELL
  standard offpage *
  page275_i22
#ISCELL
  standard offpage *
  page275_i23
#ISCELL
  standard offpage *
  page275_i24
#ISCELL
  standard offpage *
  page275_i25
#ISCELL
  logical_power universal_gnd *
  page275_i26
#CELL
  pure_quanta q_cap *
  page275_i27
#CELL
  pure_quanta q_res *
  page275_i28
#CELL
  pure_quanta q_cap *
  page275_i29
#ISCELL
  logical_power universal_gnd *
  page275_i3
#ISCELL
  logical_power universal_gnd *
  page275_i30
#CELL
  pure_quanta q_cap *
  page275_i31
#CELL
  pure_quanta q_res *
  page275_i32
#ISCELL
  logical_power vcc15 *
  page275_i33
#CELL
  pure_quanta q_res *
  page275_i34
#ISCELL
  logical_power vcc15 *
  page275_i35
#ISCELL
  logical_power universal_gnd *
  page275_i36
#CELL
  pure_quanta q_cap *
  page275_i37
#CELL
  pure_quanta q_res *
  page275_i38
#CELL
  pure_quanta q_cap *
  page275_i39
#ISCELL
  standard offpage *
  page275_i4
#CELL
  pure_quanta q_cap *
  page275_i40
#CELL
  pure_quanta q_res *
  page275_i41
#CELL
  pure_quanta q_cap *
  page275_i42
#CELL
  pure_quanta q_cap *
  page275_i43
#CELL
  pure_quanta q_inductor *
  page275_i44
#ISCELL
  logical_power universal_gnd *
  page275_i45
#CELL
  pure_quanta q_cap *
  page275_i46
#ISCELL
  logical_power vcc15 *
  page275_i47
#ISCELL
  logical_power universal_gnd *
  page275_i48
#CELL
  pure_quanta q_cap *
  page275_i49
#ISCELL
  standard offpage *
  page275_i5
#CELL
  pure_quanta q_res *
  page275_i50
#CELL
  pure_quanta q_cap *
  page275_i51
#CELL
  pure_quanta q_cap *
  page275_i52
#CELL
  pure_quanta q_res *
  page275_i53
#CELL
  pure_quanta q_cap *
  page275_i54
#CELL
  pure_quanta q_inductor *
  page275_i55
#CELL
  pure_quanta q_cap *
  page275_i56
#ISCELL
  logical_power universal_gnd *
  page275_i57
#CELL
  pure_quanta q_cap *
  page275_i58
#ISCELL
  logical_power vcc15 *
  page275_i59
#ISCELL
  standard offpage *
  page275_i6
#CELL
  pure_quanta q_cap *
  page275_i60
#CELL
  pure_quanta q_cap *
  page275_i61
#CELL
  pure_quanta q_cap *
  page275_i62
#CELL
  pure_quanta q_cap *
  page275_i63
#CELL
  pure_quanta q_res *
  page275_i64
#ISCELL
  logical_power universal_gnd *
  page275_i65
#CELL
  pure_quanta q_capp *
  page275_i66
#CELL
  pure_quanta q_capp *
  page275_i67
#CELL
  pure_quanta q_capp *
  page275_i68
#ISCELL
  logical_power vcc15 *
  page275_i69
#ISCELL
  standard offpage *
  page275_i7
#CELL
  pure_quanta q_capp *
  page275_i70
#ISCELL
  logical_power universal_gnd *
  page275_i71
#CELL
  pure_quanta q_capp *
  page275_i72
#ISCELL
  logical_power vcc15 *
  page275_i73
#CELL
  pure_quanta q_cap *
  page275_i74
#CELL
  pure_quanta q_cap *
  page275_i75
#ISCELL
  logical_power gnd *
  page275_i76
#CELL
  pure_quanta q_cap *
  page275_i77
#ISCELL
  logical_power vcc15 *
  page275_i78
#CELL
  pure_quanta q_inductor *
  page275_i79
#CELL
  pure_quanta q_cap *
  page275_i8
#CELL
  pure_quanta q_cap *
  page275_i80
#ISCELL
  logical_power universal_gnd *
  page275_i81
#ISCELL
  logical_power vcc15 *
  page275_i82
#CELL
  pure_quanta q_cap *
  page275_i83
#CELL
  pure_quanta q_cap *
  page275_i84
#CELL
  pure_quanta q_cap *
  page275_i85
#ISCELL
  logical_power universal_gnd *
  page275_i86
#CELL
  pure_quanta q_capp *
  page275_i87
#ISCELL
  logical_power vcc15 *
  page275_i88
#CELL
  pure_quanta isl99390frztr5935 *
  page275_i89
#CELL
  pure_quanta isl99390frztr5935 *
  page275_i9
